# S9S_MB_2U (Grand Teton) — schematic netlist excerpt (pin names and nets, part order shuffled) for the footprints in the layout excerpt that follows; sources: Cadence DE-HDL packaged netlist, KiCad conversion of 03242023_DA0F0TMBIJ0_F0T_Motherboard_J_brd_V01_OCP.brd

R3227  Q_RES  2.2K 5% EMPTY  pkg 0402LF  page 241 : A = SMB_1_BMC_GPU_SDA ; B = P3V3_AUX
C1993  Q_CAP_DIFFBUS  DIFF BUS_0.22UF 6.3V 20% X6S  pkg C0201  page 181 : \1\ = P3E_PCH_E1S_TX_DP<1> ; \2\ = P3E_PCH_E1S_TX_C_DP<1>

(kicad_pcb
	(version 20260206)
	(generator "pcbnew")
	(generator_version "10.0")
	(general
		(thickness 1.6)
		(legacy_teardrops no)
	)
	(paper "A4")
	(title_block
		(title "03242023_DA0F0TMBIJ0_F0T_Motherboard_J_brd_V01_OCP.brd")
		(comment 1 "Grand Teton / footprints 1640-1641 of 6105")
	)
	(layers
		(0 "F.Cu" signal "TOP")
		(4 "In1.Cu" signal "GND")
		(6 "In2.Cu" signal "IN1")
		(8 "In3.Cu" signal "GND1")
		(10 "In4.Cu" signal "IN2")
		(12 "In5.Cu" signal "GND2")
		(14 "In6.Cu" signal "IN3")
		(16 "In7.Cu" signal "GND3")
		(18 "In8.Cu" signal "VCC")
		(20 "In9.Cu" signal "VCC1")
		(22 "In10.Cu" signal "GND4")
		(24 "In11.Cu" signal "IN4")
		(26 "In12.Cu" signal "GND5")
		(28 "In13.Cu" signal "IN5")
		(30 "In14.Cu" signal "GND6")
		(32 "In15.Cu" signal "IN6")
		(34 "In16.Cu" signal "GND7")
		(2 "B.Cu" signal "BOTTOM")
		(9 "F.Adhes" user "F.Adhesive")
		(11 "B.Adhes" user "B.Adhesive")
		(13 "F.Paste" user "Package Geometry/Pastemask Top")
		(15 "B.Paste" user "Package Geometry/Pastemask Bottom")
		(5 "F.SilkS" user "Ref Des/Silkscreen Top")
		(7 "B.SilkS" user "Ref Des/Silkscreen Bottom")
		(1 "F.Mask" user "Board Geometry/Soldermask Top")
		(3 "B.Mask" user "Board Geometry/Soldermask Bottom")
		(17 "Dwgs.User" user "User.Drawings")
		(19 "Cmts.User" user "User.Comments")
		(21 "Eco1.User" user "User.Eco1")
		(23 "Eco2.User" user "User.Eco2")
		(25 "Edge.Cuts" user "Board Geometry/Outline")
		(27 "Margin" user)
		(31 "F.CrtYd" user "Package Geometry/Place Bound Top")
		(29 "B.CrtYd" user "Package Geometry/Place Bound Bottom")
		(35 "F.Fab" user "Ref Des/Assembly Top")
		(33 "B.Fab" user "Ref Des/Assembly Bottom")
	)
	(footprint ""
		(layer "F.Cu")
		(at 239.152684 -53.821838 180)
		(property "Reference" "C1993"
			(at 0 0 180)
			(layer "F.SilkS")
			(hide yes)
			(effects
				(font
					(size 1.27 1.27)
				)
			)
		)
		(property "Value" ""
			(at 0 0 180)
			(layer "F.Fab")
			(effects
				(font
					(size 1.27 1.27)
				)
			)
		)
		(duplicate_pad_numbers_are_jumpers no)
		(fp_line
			(start 0.299974 0.150114)
			(end -0.299974 0.150114)
			(stroke
				(width 0.1)
				(type default)
			)
			(layer "F.Fab")
		)
		(fp_line
			(start 0.299974 -0.150114)
			(end 0.299974 0.150114)
			(stroke
				(width 0.1)
				(type default)
			)
			(layer "F.Fab")
		)
		(fp_line
			(start -0.299974 0.150114)
			(end -0.299974 -0.150114)
			(stroke
				(width 0.1)
				(type default)
			)
			(layer "F.Fab")
		)
		(fp_line
			(start -0.299974 -0.150114)
			(end 0.299974 -0.150114)
			(stroke
				(width 0.1)
				(type default)
			)
			(layer "F.Fab")
		)
		(pad "1" smd rect
			(at -0.2667 0 180)
			(size 0.3048 0.381)
			(layers "F.Cu" "F.Mask" "F.Paste")
			(net "P3E_PCH_E1S_TX_DP<1>")
		)
		(pad "2" smd rect
			(at 0.2667 0 180)
			(size 0.3048 0.381)
			(layers "F.Cu" "F.Mask" "F.Paste")
			(net "P3E_PCH_E1S_TX_C_DP<1>")
		)
		(zone
			(layer "In1.Cu")
			(hatch none 0.5)
			(connect_pads
				(clearance 0)
			)
			(min_thickness 0.25)
			(keepout
				(tracks not_allowed)
				(vias allowed)
				(pads allowed)
				(copperpour not_allowed)
				(footprints allowed)
			)
			(placement
				(enabled no)
				(sheetname "")
			)
			(fill
				(thermal_gap 0.5)
				(thermal_bridge_width 0.5)
				(island_removal_mode 0)
			)
			(polygon
				(pts
					(arc
						(start 239.012984 -54.062122)
						(mid 239.066866 -54.039804)
						(end 239.089184 -53.985922)
					)
					(arc
						(start 239.089184 -53.655722)
						(mid 239.066866 -53.60184)
						(end 239.012984 -53.579522)
					)
					(arc
						(start 238.758984 -53.579522)
						(mid 238.705102 -53.60184)
						(end 238.682784 -53.655722)
					)
					(arc
						(start 238.682784 -53.985922)
						(mid 238.705102 -54.039804)
						(end 238.758984 -54.062122)
					)
				)
			)
		)
		(zone
			(layer "In1.Cu")
			(hatch none 0.5)
			(connect_pads
				(clearance 0)
			)
			(min_thickness 0.25)
			(keepout
				(tracks not_allowed)
				(vias allowed)
				(pads allowed)
				(copperpour not_allowed)
				(footprints allowed)
			)
			(placement
				(enabled no)
				(sheetname "")
			)
			(fill
				(thermal_gap 0.5)
				(thermal_bridge_width 0.5)
				(island_removal_mode 0)
			)
			(polygon
				(pts
					(arc
						(start 239.546384 -54.062122)
						(mid 239.600266 -54.039804)
						(end 239.622584 -53.985922)
					)
					(arc
						(start 239.622584 -53.655722)
						(mid 239.600266 -53.60184)
						(end 239.546384 -53.579522)
					)
					(arc
						(start 239.292384 -53.579522)
						(mid 239.238502 -53.60184)
						(end 239.216184 -53.655722)
					)
					(arc
						(start 239.216184 -53.985922)
						(mid 239.238502 -54.039804)
						(end 239.292384 -54.062122)
					)
				)
			)
		)
	)
	(footprint ""
		(layer "F.Cu")
		(at 53.87848 -433.898548 -90)
		(property "Reference" "R3227"
			(at 0 0 270)
			(layer "F.SilkS")
			(hide yes)
			(effects
				(font
					(size 1.27 1.27)
				)
			)
		)
		(property "Value" ""
			(at 0 0 270)
			(layer "F.Fab")
			(effects
				(font
					(size 1.27 1.27)
				)
			)
		)
		(duplicate_pad_numbers_are_jumpers no)
		(fp_line
			(start -0.7874 0.4064)
			(end -0.7874 -0.4064)
			(stroke
				(width 0.1524)
				(type default)
			)
			(layer "F.SilkS")
		)
		(fp_line
			(start 0.7874 0.4064)
			(end -0.7874 0.4064)
			(stroke
				(width 0.1524)
				(type default)
			)
			(layer "F.SilkS")
		)
		(fp_line
			(start -0.7874 -0.4064)
			(end 0.7874 -0.4064)
			(stroke
				(width 0.1524)
				(type default)
			)
			(layer "F.SilkS")
		)
		(fp_line
			(start 0.7874 -0.4064)
			(end 0.7874 0.4064)
			(stroke
				(width 0.1524)
				(type default)
			)
			(layer "F.SilkS")
		)
		(fp_line
			(start -0.67945 0.3048)
			(end -0.67945 -0.305054)
			(stroke
				(width 0.1)
				(type default)
			)
			(layer "F.Fab")
		)
		(fp_line
			(start -0.12065 0.3048)
			(end -0.67945 0.3048)
			(stroke
				(width 0.1)
				(type default)
			)
			(layer "F.Fab")
		)
		(fp_line
			(start 0.120396 0.3048)
			(end 0.120396 0.2794)
			(stroke
				(width 0.1)
				(type default)
			)
			(layer "F.Fab")
		)
		(fp_line
			(start 0.67945 0.3048)
			(end 0.120396 0.3048)
			(stroke
				(width 0.1)
				(type default)
			)
			(layer "F.Fab")
		)
		(fp_line
			(start -0.12065 0.2794)
			(end -0.12065 0.3048)
			(stroke
				(width 0.1)
				(type default)
			)
			(layer "F.Fab")
		)
		(fp_line
			(start 0.120396 0.2794)
			(end -0.12065 0.2794)
			(stroke
				(width 0.1)
				(type default)
			)
			(layer "F.Fab")
		)
		(fp_line
			(start -0.12065 -0.2794)
			(end 0.12065 -0.2794)
			(stroke
				(width 0.1)
				(type default)
			)
			(layer "F.Fab")
		)
		(fp_line
			(start 0.12065 -0.2794)
			(end 0.12065 -0.3048)
			(stroke
				(width 0.1)
				(type default)
			)
			(layer "F.Fab")
		)
		(fp_line
			(start 0.12065 -0.3048)
			(end 0.67945 -0.3048)
			(stroke
				(width 0.1)
				(type default)
			)
			(layer "F.Fab")
		)
		(fp_line
			(start 0.67945 -0.3048)
			(end 0.67945 0.3048)
			(stroke
				(width 0.1)
				(type default)
			)
			(layer "F.Fab")
		)
		(fp_line
			(start -0.67945 -0.305054)
			(end -0.12065 -0.305054)
			(stroke
				(width 0.1)
				(type default)
			)
			(layer "F.Fab")
		)
		(fp_line
			(start -0.12065 -0.305054)
			(end -0.12065 -0.2794)
			(stroke
				(width 0.1)
				(type default)
			)
			(layer "F.Fab")
		)
		(pad "1" smd circle
			(at -0.40005 0 270)
			(size 0 0)
			(layers "F.Cu" "F.Mask" "F.Paste")
			(net "SMB_1_BMC_GPU_SDA")
		)
		(pad "2" smd circle
			(at 0.40005 0 270)
			(size 0 0)
			(layers "F.Cu" "F.Mask" "F.Paste")
			(net "P3V3_AUX")
		)
	)
)
